# S9S_MB_2U (Grand Teton) — schematic netlist excerpt (pin names and nets, part order shuffled) for the footprints in the layout excerpt that follows; sources: Cadence DE-HDL packaged netlist, KiCad conversion of 03242023_DA0F0TMBIJ0_F0T_Motherboard_J_brd_V01_OCP.brd

C741  Q_CAP_DIFFBUS  DIFF BUS_0.22UF 6.3V 20% X6S  pkg C0201  page 176 : \1\ = P5E_CPU1_PE0_TX_C_DP<0> ; \2\ = P5E_CPU1_PE0_TX_DP<0>
PR639  Q_RES  0 5% CHIP  pkg 0402LF  page 285 : A = P5V ; B = PVCCIN_CPU1_PVCC
R4784  Q_RES  10K 1% EMPTY  pkg 0402LF  page 307 : A = P3V3_AUX ; B = FM_UV_ADR_TRIGGER_N

(kicad_pcb
	(version 20260206)
	(generator "pcbnew")
	(generator_version "10.0")
	(general
		(thickness 1.6)
		(legacy_teardrops no)
	)
	(paper "A4")
	(title_block
		(title "03242023_DA0F0TMBIJ0_F0T_Motherboard_J_brd_V01_OCP.brd")
		(comment 1 "Grand Teton / footprints 2090-2092 of 6105")
	)
	(layers
		(0 "F.Cu" signal "TOP")
		(4 "In1.Cu" signal "GND")
		(6 "In2.Cu" signal "IN1")
		(8 "In3.Cu" signal "GND1")
		(10 "In4.Cu" signal "IN2")
		(12 "In5.Cu" signal "GND2")
		(14 "In6.Cu" signal "IN3")
		(16 "In7.Cu" signal "GND3")
		(18 "In8.Cu" signal "VCC")
		(20 "In9.Cu" signal "VCC1")
		(22 "In10.Cu" signal "GND4")
		(24 "In11.Cu" signal "IN4")
		(26 "In12.Cu" signal "GND5")
		(28 "In13.Cu" signal "IN5")
		(30 "In14.Cu" signal "GND6")
		(32 "In15.Cu" signal "IN6")
		(34 "In16.Cu" signal "GND7")
		(2 "B.Cu" signal "BOTTOM")
		(9 "F.Adhes" user "F.Adhesive")
		(11 "B.Adhes" user "B.Adhesive")
		(13 "F.Paste" user "Package Geometry/Pastemask Top")
		(15 "B.Paste" user "Package Geometry/Pastemask Bottom")
		(5 "F.SilkS" user "Ref Des/Silkscreen Top")
		(7 "B.SilkS" user "Ref Des/Silkscreen Bottom")
		(1 "F.Mask" user "Board Geometry/Soldermask Top")
		(3 "B.Mask" user "Board Geometry/Soldermask Bottom")
		(17 "Dwgs.User" user "User.Drawings")
		(19 "Cmts.User" user "User.Comments")
		(21 "Eco1.User" user "User.Eco1")
		(23 "Eco2.User" user "User.Eco2")
		(25 "Edge.Cuts" user "Board Geometry/Outline")
		(27 "Margin" user)
		(31 "F.CrtYd" user "Package Geometry/Place Bound Top")
		(29 "B.CrtYd" user "Package Geometry/Place Bound Bottom")
		(35 "F.Fab" user "Ref Des/Assembly Top")
		(33 "B.Fab" user "Ref Des/Assembly Bottom")
	)
	(footprint ""
		(layer "F.Cu")
		(at 94.817438 -402.371052 -90)
		(property "Reference" "C741"
			(at 0 0 270)
			(layer "F.SilkS")
			(hide yes)
			(effects
				(font
					(size 1.27 1.27)
				)
			)
		)
		(property "Value" ""
			(at 0 0 270)
			(layer "F.Fab")
			(effects
				(font
					(size 1.27 1.27)
				)
			)
		)
		(duplicate_pad_numbers_are_jumpers no)
		(fp_line
			(start -0.299974 0.150114)
			(end -0.299974 -0.150114)
			(stroke
				(width 0.1)
				(type default)
			)
			(layer "F.Fab")
		)
		(fp_line
			(start 0.299974 0.150114)
			(end -0.299974 0.150114)
			(stroke
				(width 0.1)
				(type default)
			)
			(layer "F.Fab")
		)
		(fp_line
			(start -0.299974 -0.150114)
			(end 0.299974 -0.150114)
			(stroke
				(width 0.1)
				(type default)
			)
			(layer "F.Fab")
		)
		(fp_line
			(start 0.299974 -0.150114)
			(end 0.299974 0.150114)
			(stroke
				(width 0.1)
				(type default)
			)
			(layer "F.Fab")
		)
		(pad "1" smd rect
			(at -0.2667 0 270)
			(size 0.3048 0.381)
			(layers "F.Cu" "F.Mask" "F.Paste")
			(net "P5E_CPU1_PE0_TX_C_DP<0>")
		)
		(pad "2" smd rect
			(at 0.2667 0 270)
			(size 0.3048 0.381)
			(layers "F.Cu" "F.Mask" "F.Paste")
			(net "P5E_CPU1_PE0_TX_DP<0>")
		)
	)
	(footprint ""
		(layer "F.Cu")
		(at 144.54378 -344.232738 180)
		(property "Reference" "PR639"
			(at 0 0 180)
			(layer "F.SilkS")
			(hide yes)
			(effects
				(font
					(size 1.27 1.27)
				)
			)
		)
		(property "Value" ""
			(at 0 0 180)
			(layer "F.Fab")
			(effects
				(font
					(size 1.27 1.27)
				)
			)
		)
		(duplicate_pad_numbers_are_jumpers no)
		(fp_line
			(start 0.7874 0.4064)
			(end -0.7874 0.4064)
			(stroke
				(width 0.1524)
				(type default)
			)
			(layer "F.SilkS")
		)
		(fp_line
			(start 0.7874 -0.4064)
			(end 0.7874 0.4064)
			(stroke
				(width 0.1524)
				(type default)
			)
			(layer "F.SilkS")
		)
		(fp_line
			(start -0.7874 0.4064)
			(end -0.7874 -0.4064)
			(stroke
				(width 0.1524)
				(type default)
			)
			(layer "F.SilkS")
		)
		(fp_line
			(start -0.7874 -0.4064)
			(end 0.7874 -0.4064)
			(stroke
				(width 0.1524)
				(type default)
			)
			(layer "F.SilkS")
		)
		(fp_line
			(start 0.67945 0.3048)
			(end 0.120396 0.3048)
			(stroke
				(width 0.1)
				(type default)
			)
			(layer "F.Fab")
		)
		(fp_line
			(start 0.67945 -0.3048)
			(end 0.67945 0.3048)
			(stroke
				(width 0.1)
				(type default)
			)
			(layer "F.Fab")
		)
		(fp_line
			(start 0.12065 -0.2794)
			(end 0.12065 -0.3048)
			(stroke
				(width 0.1)
				(type default)
			)
			(layer "F.Fab")
		)
		(fp_line
			(start 0.12065 -0.3048)
			(end 0.67945 -0.3048)
			(stroke
				(width 0.1)
				(type default)
			)
			(layer "F.Fab")
		)
		(fp_line
			(start 0.120396 0.3048)
			(end 0.120396 0.2794)
			(stroke
				(width 0.1)
				(type default)
			)
			(layer "F.Fab")
		)
		(fp_line
			(start 0.120396 0.2794)
			(end -0.12065 0.2794)
			(stroke
				(width 0.1)
				(type default)
			)
			(layer "F.Fab")
		)
		(fp_line
			(start -0.12065 0.3048)
			(end -0.67945 0.3048)
			(stroke
				(width 0.1)
				(type default)
			)
			(layer "F.Fab")
		)
		(fp_line
			(start -0.12065 0.2794)
			(end -0.12065 0.3048)
			(stroke
				(width 0.1)
				(type default)
			)
			(layer "F.Fab")
		)
		(fp_line
			(start -0.12065 -0.2794)
			(end 0.12065 -0.2794)
			(stroke
				(width 0.1)
				(type default)
			)
			(layer "F.Fab")
		)
		(fp_line
			(start -0.12065 -0.305054)
			(end -0.12065 -0.2794)
			(stroke
				(width 0.1)
				(type default)
			)
			(layer "F.Fab")
		)
		(fp_line
			(start -0.67945 0.3048)
			(end -0.67945 -0.305054)
			(stroke
				(width 0.1)
				(type default)
			)
			(layer "F.Fab")
		)
		(fp_line
			(start -0.67945 -0.305054)
			(end -0.12065 -0.305054)
			(stroke
				(width 0.1)
				(type default)
			)
			(layer "F.Fab")
		)
		(pad "1" smd circle
			(at -0.40005 0 180)
			(size 0 0)
			(layers "F.Cu" "F.Mask" "F.Paste")
			(net "P5V")
		)
		(pad "2" smd circle
			(at 0.40005 0 180)
			(size 0 0)
			(layers "F.Cu" "F.Mask" "F.Paste")
			(net "PVCCIN_CPU1_PVCC")
		)
	)
	(footprint ""
		(layer "F.Cu")
		(at 207.772 -97.6884 90)
		(property "Reference" "R4784"
			(at 0 0 90)
			(layer "F.SilkS")
			(hide yes)
			(effects
				(font
					(size 1.27 1.27)
				)
			)
		)
		(property "Value" ""
			(at 0 0 90)
			(layer "F.Fab")
			(effects
				(font
					(size 1.27 1.27)
				)
			)
		)
		(duplicate_pad_numbers_are_jumpers no)
		(fp_line
			(start 0.7874 -0.4064)
			(end 0.7874 0.4064)
			(stroke
				(width 0.1524)
				(type default)
			)
			(layer "F.SilkS")
		)
		(fp_line
			(start -0.7874 -0.4064)
			(end 0.7874 -0.4064)
			(stroke
				(width 0.1524)
				(type default)
			)
			(layer "F.SilkS")
		)
		(fp_line
			(start 0.7874 0.4064)
			(end -0.7874 0.4064)
			(stroke
				(width 0.1524)
				(type default)
			)
			(layer "F.SilkS")
		)
		(fp_line
			(start -0.7874 0.4064)
			(end -0.7874 -0.4064)
			(stroke
				(width 0.1524)
				(type default)
			)
			(layer "F.SilkS")
		)
		(fp_line
			(start -0.12065 -0.305054)
			(end -0.12065 -0.2794)
			(stroke
				(width 0.1)
				(type default)
			)
			(layer "F.Fab")
		)
		(fp_line
			(start -0.67945 -0.305054)
			(end -0.12065 -0.305054)
			(stroke
				(width 0.1)
				(type default)
			)
			(layer "F.Fab")
		)
		(fp_line
			(start 0.67945 -0.3048)
			(end 0.67945 0.3048)
			(stroke
				(width 0.1)
				(type default)
			)
			(layer "F.Fab")
		)
		(fp_line
			(start 0.12065 -0.3048)
			(end 0.67945 -0.3048)
			(stroke
				(width 0.1)
				(type default)
			)
			(layer "F.Fab")
		)
		(fp_line
			(start 0.12065 -0.2794)
			(end 0.12065 -0.3048)
			(stroke
				(width 0.1)
				(type default)
			)
			(layer "F.Fab")
		)
		(fp_line
			(start -0.12065 -0.2794)
			(end 0.12065 -0.2794)
			(stroke
				(width 0.1)
				(type default)
			)
			(layer "F.Fab")
		)
		(fp_line
			(start 0.120396 0.2794)
			(end -0.12065 0.2794)
			(stroke
				(width 0.1)
				(type default)
			)
			(layer "F.Fab")
		)
		(fp_line
			(start -0.12065 0.2794)
			(end -0.12065 0.3048)
			(stroke
				(width 0.1)
				(type default)
			)
			(layer "F.Fab")
		)
		(fp_line
			(start 0.67945 0.3048)
			(end 0.120396 0.3048)
			(stroke
				(width 0.1)
				(type default)
			)
			(layer "F.Fab")
		)
		(fp_line
			(start 0.120396 0.3048)
			(end 0.120396 0.2794)
			(stroke
				(width 0.1)
				(type default)
			)
			(layer "F.Fab")
		)
		(fp_line
			(start -0.12065 0.3048)
			(end -0.67945 0.3048)
			(stroke
				(width 0.1)
				(type default)
			)
			(layer "F.Fab")
		)
		(fp_line
			(start -0.67945 0.3048)
			(end -0.67945 -0.305054)
			(stroke
				(width 0.1)
				(type default)
			)
			(layer "F.Fab")
		)
		(pad "1" smd circle
			(at -0.40005 0 90)
			(size 0 0)
			(layers "F.Cu" "F.Mask" "F.Paste")
			(net "P3V3_AUX")
		)
		(pad "2" smd circle
			(at 0.40005 0 90)
			(size 0 0)
			(layers "F.Cu" "F.Mask" "F.Paste")
			(net "FM_UV_ADR_TRIGGER_N")
		)
	)
)
